# T6G (Grand Teton) — schematic netlist excerpt (pin names and nets, part order shuffled) for the footprints in the layout excerpt that follows; sources: Cadence DE-HDL packaged netlist, KiCad conversion of 04192023_DAF0TMB3IC0_F0TG_MB_C_brd_V02_OCP.brd

J102  SCONN288_DDR506112002KQ  IO  pkg DDR288S_1-1VXC  page 104
  VIN_BULK0  = P12V_MEM_CPU1
  RFU0  = NC
  VIN_MGMT  = P3V3_AUX
  HSCL  = I3C_SPD_DDRG_CPU1_SCL
  HSDA  = I3C_SPD_DDRG_CPU1_SDA
  VSS0  = GND
  DQ0_A  = M_G_CPU1_SA_DQ<0>
  VSS1  = GND
  DQ1_A  = M_G_CPU1_SA_DQ<1>
  VSS2  = GND
  DQS0_A_T  = M_G_CPU1_SA_DQS_DP<0>
  DQS0_A_C  = M_G_CPU1_SA_DQS_DN<0>
  VSS3  = GND
  DQ4_A  = M_G_CPU1_SA_DQ<4>
  VSS4  = GND
  DQ5_A  = M_G_CPU1_SA_DQ<5>
  VSS5  = GND
  DQ8_A  = M_G_CPU1_SA_DQ<8>
  VSS6  = GND
  DQ9_A  = M_G_CPU1_SA_DQ<9>
  VSS7  = GND
  DQS1_A_T  = M_G_CPU1_SA_DQS_DP<1>
  DQS1_A_C  = M_G_CPU1_SA_DQS_DN<1>
  VSS8  = GND
  DQ12_A  = M_G_CPU1_SA_DQ<12>
  VSS9  = GND
  DQ13_A  = M_G_CPU1_SA_DQ<13>
  VSS10  = GND
  DQ16_A  = M_G_CPU1_SA_DQ<16>
  VSS11  = GND
  DQ17_A  = M_G_CPU1_SA_DQ<17>
  VSS12  = GND
  DQS2_A_T  = M_G_CPU1_SA_DQS_DP<2>
  DQS2_A_C  = M_G_CPU1_SA_DQS_DN<2>
  VSS13  = GND
  DQ20_A  = M_G_CPU1_SA_DQ<20>
  VSS14  = GND
  DQ21_A  = M_G_CPU1_SA_DQ<21>
  VSS15  = GND
  DQ24_A  = M_G_CPU1_SA_DQ<24>
  VSS16  = GND
  DQ25_A  = M_G_CPU1_SA_DQ<25>
  VSS17  = GND
  DQS3_A_T  = M_G_CPU1_SA_DQS_DP<3>
  DQS3_A_C  = M_G_CPU1_SA_DQS_DN<3>
  VSS18  = GND
  DQ28_A  = M_G_CPU1_SA_DQ<28>
  VSS19  = GND
  DQ29_A  = M_G_CPU1_SA_DQ<29>
  VSS20  = GND
  CB0_A  = M_G_CPU1_SA_CB<0>
  VSS21  = GND
  CB1_A  = M_G_CPU1_SA_CB<1>
  VSS22  = GND
  DQS4_A_T  = M_G_CPU1_SA_DQS_DP<4>
  DQS4_A_C  = M_G_CPU1_SA_DQS_DN<4>
  VSS23  = GND
  CB4_A  = M_G_CPU1_SA_CB<4>
  VSS24  = GND
  CB5_A  = M_G_CPU1_SA_CB<5>
  VSS25  = GND
  ALERT_N  = M_G_CPU1_ALERT_N
  VSS26  = GND
  CS0_A_N  = M_G_CPU1_SA_CS_N<0>
  VSS27  = GND
  CA0_A  = M_G_CPU1_SA_CA<0>
  VSS28  = GND
  CA2_A  = M_G_CPU1_SA_CA<2>
  VSS29  = GND
  CA4_A  = M_G_CPU1_SA_CA<4>
  VSS30  = GND
  CA6_A  = M_G_CPU1_SA_CA<6>
  VSS31  = GND
  PAR_A  = M_G_CPU1_SA_PAR
  VSS32  = GND
  CA0_B  = M_G_CPU1_SB_CA<0>
  VSS33  = GND
  CA2_B  = M_G_CPU1_SB_CA<2>
  VSS34  = GND
  CA4_B  = M_G_CPU1_SB_CA<4>
  VSS35  = GND
  CA6_B  = M_G_CPU1_SB_CA<6>
  VSS36  = GND
  CS0_B_N  = M_G_CPU1_SB_CS_N<0>
  VSS37  = GND
  \lbd||rsp_a_n\  = M_G_CPU1_SA_RSP<0>
  \lbs||rsp_b_n\  = M_G_CPU1_SB_RSP<0>
  VSS38  = GND
  CB4_B  = M_G_CPU1_SB_CB<4>
  VSS39  = GND
  CB5_B  = M_G_CPU1_SB_CB<5>
  VSS40  = GND
  \dqs9_b_t||tdqs9_b_t||dbi4_b_n\  = M_G_CPU1_SB_DQS_DP<9>
  \dqs9_b_c||tdqs9_b_c\  = M_G_CPU1_SB_DQS_DN<9>
  VSS41  = GND
  CB0_B  = M_G_CPU1_SB_CB<0>
  VSS42  = GND
  CB1_B  = M_G_CPU1_SB_CB<1>
  VSS43  = GND
  DQ0_B  = M_G_CPU1_SB_DQ<0>
  VSS44  = GND
  DQ1_B  = M_G_CPU1_SB_DQ<1>
  VSS45  = GND
  DQS0_B_T  = M_G_CPU1_SB_DQS_DP<0>
  DQS0_B_C  = M_G_CPU1_SB_DQS_DN<0>
  VSS46  = GND
  DQ4_B  = M_G_CPU1_SB_DQ<4>
  VSS47  = GND
  DQ5_B  = M_G_CPU1_SB_DQ<5>
  VSS48  = GND
  DQ8_B  = M_G_CPU1_SB_DQ<8>
  VSS49  = GND
  DQ9_B  = M_G_CPU1_SB_DQ<9>
  VSS50  = GND
  DQS1_B_T  = M_G_CPU1_SB_DQS_DP<1>
  DQS1_B_C  = M_G_CPU1_SB_DQS_DN<1>
  VSS51  = GND
  DQ12_B  = M_G_CPU1_SB_DQ<12>
  VSS52  = GND
  DQ13_B  = M_G_CPU1_SB_DQ<13>
  VSS53  = GND
  DQ16_B  = M_G_CPU1_SB_DQ<16>
  VSS54  = GND
  DQ17_B  = M_G_CPU1_SB_DQ<17>
  VSS55  = GND
  DQS2_B_T  = M_G_CPU1_SB_DQS_DP<2>
  DQS2_B_C  = M_G_CPU1_SB_DQS_DN<2>
  VSS56  = GND
  DQ20_B  = M_G_CPU1_SB_DQ<20>
  VSS57  = GND
  DQ21_B  = M_G_CPU1_SB_DQ<21>
  VSS58  = GND
  DQ24_B  = M_G_CPU1_SB_DQ<24>
  VSS59  = GND
  DQ25_B  = M_G_CPU1_SB_DQ<25>
  VSS60  = GND
  DQS3_B_T  = M_G_CPU1_SB_DQS_DP<3>
  DQS3_B_C  = M_G_CPU1_SB_DQS_DN<3>
  VSS61  = GND
  DQ28_B  = M_G_CPU1_SB_DQ<28>
  VSS62  = GND
  DQ29_B  = M_G_CPU1_SB_DQ<29>
  VSS63  = GND
  RFU1  = NC
  VIN_BULK1  = P12V_MEM_CPU1
  VIN_BULK2  = P12V_MEM_CPU1
  \pwr_good||fail_n\  = PWRGD_CHG_CPU1_DIMM0
  HAS  = PD_CHG_CPU1_DIMM0_SAA
  RFU2  = NC
  RFU3  = NC
  VSS64  = GND
  DQ2_A  = M_G_CPU1_SA_DQ<2>
  VSS65  = GND
  DQ3_A  = M_G_CPU1_SA_DQ<3>
  VSS66  = GND
  \dqs5_a_c||tdqs5_a_c||dqs5_a_t||tdqs5_a_t\  = M_G_CPU1_SA_DQS_DN<5>
  \dqs5_a_t||tdqs5_a_t\  = M_G_CPU1_SA_DQS_DP<5>
  VSS67  = GND
  DQ6_A  = M_G_CPU1_SA_DQ<6>
  VSS68  = GND
  DQ7_A  = M_G_CPU1_SA_DQ<7>
  VSS69  = GND
  DQ10_A  = M_G_CPU1_SA_DQ<10>
  VSS70  = GND
  DQ11_A  = M_G_CPU1_SA_DQ<11>
  VSS71  = GND
  \dqs6_a_c||tdqs6_a_c||dqs6_a_t||tdqs6_a_t\  = M_G_CPU1_SA_DQS_DN<6>
  \dqs6_a_t||tdqs6_a_t\  = M_G_CPU1_SA_DQS_DP<6>
  VSS72  = GND
  DQ14_A  = M_G_CPU1_SA_DQ<14>
  VSS73  = GND
  DQ15_A  = M_G_CPU1_SA_DQ<15>
  VSS74  = GND
  DQ18_A  = M_G_CPU1_SA_DQ<18>
  VSS75  = GND
  DQ19_A  = M_G_CPU1_SA_DQ<19>
  VSS76  = GND
  \dqs7_a_c||tdqs7_a_c\  = M_G_CPU1_SA_DQS_DN<7>
  \dqs7_a_t||tdqs7_a_t\  = M_G_CPU1_SA_DQS_DP<7>
  VSS77  = GND
  DQ22_A  = M_G_CPU1_SA_DQ<22>
  VSS78  = GND
  DQ23_A  = M_G_CPU1_SA_DQ<23>
  VSS79  = GND
  DQ26_A  = M_G_CPU1_SA_DQ<26>
  VSS80  = GND
  DQ27_A  = M_G_CPU1_SA_DQ<27>
  VSS81  = GND
  \dqs8_a_c||tdqs8_a_c\  = M_G_CPU1_SA_DQS_DN<8>
  \dqs8_a_t||tdqs8_a_t\  = M_G_CPU1_SA_DQS_DP<8>
  VSS82  = GND
  DQ30_A  = M_G_CPU1_SA_DQ<30>
  VSS83  = GND
  DQ31_A  = M_G_CPU1_SA_DQ<31>
  VSS84  = GND
  CB2_A  = M_G_CPU1_SA_CB<2>
  VSS85  = GND
  CB3_A  = M_G_CPU1_SA_CB<3>
  VSS86  = GND
  \dqs9_a_c||tdqs9_a_c\  = M_G_CPU1_SA_DQS_DN<9>
  \dqs9_a_t||tdqs9_a_t\  = M_G_CPU1_SA_DQS_DP<9>
  VSS87  = GND
  CB6_A  = M_G_CPU1_SA_CB<6>
  VSS88  = GND
  CB7_A  = M_G_CPU1_SA_CB<7>
  VSS89  = GND
  RESET_N  = M_G_CPU1_RESET_N
  VSS90  = GND
  CS1_A_N  = M_G_CPU1_SA_CS_N<1>
  VSS91  = GND
  CA1_A  = M_G_CPU1_SA_CA<1>
  VSS92  = GND
  CA3_A  = M_G_CPU1_SA_CA<3>
  VSS93  = GND
  CA5_A  = M_G_CPU1_SA_CA<5>
  VSS94  = GND
  CK_T  = M_G_CPU1_CLK_DP<0>
  CK_C  = M_G_CPU1_CLK_DN<0>
  VSS95  = GND
  RFU4  = NC
  CA1_B  = M_G_CPU1_SB_CA<1>
  VSS96  = GND
  CA3_B  = M_G_CPU1_SB_CA<3>
  VSS97  = GND
  CA5_B  = M_G_CPU1_SB_CA<5>
  VSS98  = GND
  PAR_B  = M_G_CPU1_SB_PAR
  VSS99  = GND
  CS1_B_N  = M_G_CPU1_SB_CS_N<1>
  VSS100  = GND
  RFU5  = NC
  RFU6  = NC
  VSS101  = GND
  CB6_B  = M_G_CPU1_SB_CB<6>
  VSS102  = GND
  CB7_B  = M_G_CPU1_SB_CB<7>
  VSS103  = GND
  DQS4_B_C  = M_G_CPU1_SB_DQS_DN<4>
  DQS4_B_T  = M_G_CPU1_SB_DQS_DP<4>
  VSS104  = GND
  CB2_B  = M_G_CPU1_SB_CB<2>
  VSS105  = GND
  CB3_B  = M_G_CPU1_SB_CB<3>
  VSS106  = GND
  DQ2_B  = M_G_CPU1_SB_DQ<2>
  VSS107  = GND
  DQ3_B  = M_G_CPU1_SB_DQ<3>
  VSS108  = GND
  \dqs5_b_c||tdqs5_b_c\  = M_G_CPU1_SB_DQS_DN<5>
  \dqs5_b_t||tdqs5_b_t\  = M_G_CPU1_SB_DQS_DP<5>
  VSS109  = GND
  DQ6_B  = M_G_CPU1_SB_DQ<6>
  VSS110  = GND
  DQ7_B  = M_G_CPU1_SB_DQ<7>
  VSS111  = GND
  DQ10_B  = M_G_CPU1_SB_DQ<10>
  VSS112  = GND
  DQ11_B  = M_G_CPU1_SB_DQ<11>
  VSS113  = GND
  \dqs6_b_c||tdqs6_b_c\  = M_G_CPU1_SB_DQS_DN<6>
  \dqs6_b_t||tdqs6_b_t\  = M_G_CPU1_SB_DQS_DP<6>
  VSS114  = GND
  DQ14_B  = M_G_CPU1_SB_DQ<14>
  VSS115  = GND
  DQ15_B  = M_G_CPU1_SB_DQ<15>
  VSS116  = GND
  DQ18_B  = M_G_CPU1_SB_DQ<18>
  VSS117  = GND
  DQ19_B  = M_G_CPU1_SB_DQ<19>
  VSS118  = GND
  \dqs7_b_c||tdqs7_b_c\  = M_G_CPU1_SB_DQS_DN<7>
  \dqs7_b_t||tdqs7_b_t\  = M_G_CPU1_SB_DQS_DP<7>
  VSS119  = GND
  DQ22_B  = M_G_CPU1_SB_DQ<22>
  VSS120  = GND
  DQ23_B  = M_G_CPU1_SB_DQ<23>
  VSS121  = GND
  DQ26_B  = M_G_CPU1_SB_DQ<26>
  VSS122  = GND
  DQ27_B  = M_G_CPU1_SB_DQ<27>
  VSS123  = GND
  \dqs8_b_c||tdqs8_b_c\  = M_G_CPU1_SB_DQS_DN<8>
  \dqs8_b_t||tdqs8_b_t\  = M_G_CPU1_SB_DQS_DP<8>
  VSS124  = GND
  DQ30_B  = M_G_CPU1_SB_DQ<30>
  VSS125  = GND
  DQ31_B  = M_G_CPU1_SB_DQ<31>
  VSS126  = GND
  G1  = GND
  G2  = GND
  G3  = GND

(kicad_pcb
	(version 20260206)
	(generator "pcbnew")
	(generator_version "10.0")
	(general
		(thickness 1.6)
		(legacy_teardrops no)
	)
	(paper "A4")
	(title_block
		(title "04192023_DAF0TMB3IC0_F0TG_MB_C_brd_V02_OCP.brd")
		(comment 1 "Grand Teton / footprint 4934 of 8354 (J102), pads 47-92 of 291")
	)
	(layers
		(0 "F.Cu" signal "TOP")
		(4 "In1.Cu" signal "GND")
		(6 "In2.Cu" signal "IN1")
		(8 "In3.Cu" signal "GND1")
		(10 "In4.Cu" signal "IN2")
		(12 "In5.Cu" signal "GND2")
		(14 "In6.Cu" signal "IN3")
		(16 "In7.Cu" signal "GND3")
		(18 "In8.Cu" signal "VCC")
		(20 "In9.Cu" signal "VCC1")
		(22 "In10.Cu" signal "GND4")
		(24 "In11.Cu" signal "IN4")
		(26 "In12.Cu" signal "GND5")
		(28 "In13.Cu" signal "IN5")
		(30 "In14.Cu" signal "GND6")
		(32 "In15.Cu" signal "IN6")
		(34 "In16.Cu" signal "GND7")
		(2 "B.Cu" signal "BOTTOM")
		(9 "F.Adhes" user "F.Adhesive")
		(11 "B.Adhes" user "B.Adhesive")
		(13 "F.Paste" user "Package Geometry/Pastemask Top")
		(15 "B.Paste" user "Package Geometry/Pastemask Bottom")
		(5 "F.SilkS" user "Ref Des/Silkscreen Top")
		(7 "B.SilkS" user "Ref Des/Silkscreen Bottom")
		(1 "F.Mask" user "Board Geometry/Soldermask Top")
		(3 "B.Mask" user "Board Geometry/Soldermask Bottom")
		(17 "Dwgs.User" user "User.Drawings")
		(19 "Cmts.User" user "User.Comments")
		(21 "Eco1.User" user "User.Eco1")
		(23 "Eco2.User" user "User.Eco2")
		(25 "Edge.Cuts" user "Board Geometry/Outline")
		(27 "Margin" user)
		(31 "F.CrtYd" user "Package Geometry/Place Bound Top")
		(29 "B.CrtYd" user "Package Geometry/Place Bound Bottom")
		(35 "F.Fab" user "Ref Des/Assembly Top")
		(33 "B.Fab" user "Ref Des/Assembly Bottom")
	)
	(footprint ""
		(layer "F.Cu")
		(at 166.47795 -255.560322 180)
		(property "Reference" "J102"
			(at -2.7178 -81.857088 0)
			(unlocked yes)
			(layer "F.SilkS")
			(effects
				(font
					(size 0.7874 0.5842)
					(thickness 0.1524)
				)
			)
		)
		(property "Value" ""
			(at 0 0 180)
			(layer "F.Fab")
			(effects
				(font
					(size 1.27 1.27)
				)
			)
		)
		(duplicate_pad_numbers_are_jumpers no)
		(pad "47" smd rect
			(at -2.050034 -24.224996 90)
			(size 0.519938 1.4986)
			(layers "F.Cu" "F.Mask" "F.Paste")
			(net "M_G_CPU1_SA_DQ<28>")
		)
		(pad "48" smd rect
			(at -2.050034 -23.375112 90)
			(size 0.519938 1.4986)
			(layers "F.Cu" "F.Mask" "F.Paste")
			(net "GND")
		)
		(pad "49" smd rect
			(at -2.050034 -22.524974 90)
			(size 0.519938 1.4986)
			(layers "F.Cu" "F.Mask" "F.Paste")
			(net "M_G_CPU1_SA_DQ<29>")
		)
		(pad "50" smd rect
			(at -2.050034 -21.67509 90)
			(size 0.519938 1.4986)
			(layers "F.Cu" "F.Mask" "F.Paste")
			(net "GND")
		)
		(pad "51" smd rect
			(at -2.050034 -20.824952 90)
			(size 0.519938 1.4986)
			(layers "F.Cu" "F.Mask" "F.Paste")
			(net "M_G_CPU1_SA_CB<0>")
		)
		(pad "52" smd rect
			(at -2.050034 -19.975068 90)
			(size 0.519938 1.4986)
			(layers "F.Cu" "F.Mask" "F.Paste")
			(net "GND")
		)
		(pad "53" smd rect
			(at -2.050034 -19.12493 90)
			(size 0.519938 1.4986)
			(layers "F.Cu" "F.Mask" "F.Paste")
			(net "M_G_CPU1_SA_CB<1>")
		)
		(pad "54" smd rect
			(at -2.050034 -18.275046 90)
			(size 0.519938 1.4986)
			(layers "F.Cu" "F.Mask" "F.Paste")
			(net "GND")
		)
		(pad "55" smd rect
			(at -2.050034 -17.424908 90)
			(size 0.519938 1.4986)
			(layers "F.Cu" "F.Mask" "F.Paste")
			(net "M_G_CPU1_SA_DQS_DP<4>")
		)
		(pad "56" smd rect
			(at -2.050034 -16.575024 90)
			(size 0.519938 1.4986)
			(layers "F.Cu" "F.Mask" "F.Paste")
			(net "M_G_CPU1_SA_DQS_DN<4>")
		)
		(pad "57" smd rect
			(at -2.050034 -15.724886 90)
			(size 0.519938 1.4986)
			(layers "F.Cu" "F.Mask" "F.Paste")
			(net "GND")
		)
		(pad "58" smd rect
			(at -2.050034 -14.875002 90)
			(size 0.519938 1.4986)
			(layers "F.Cu" "F.Mask" "F.Paste")
			(net "M_G_CPU1_SA_CB<4>")
		)
		(pad "59" smd rect
			(at -2.050034 -14.025118 90)
			(size 0.519938 1.4986)
			(layers "F.Cu" "F.Mask" "F.Paste")
			(net "GND")
		)
		(pad "60" smd rect
			(at -2.050034 -13.17498 90)
			(size 0.519938 1.4986)
			(layers "F.Cu" "F.Mask" "F.Paste")
			(net "M_G_CPU1_SA_CB<5>")
		)
		(pad "61" smd rect
			(at -2.050034 -12.325096 90)
			(size 0.519938 1.4986)
			(layers "F.Cu" "F.Mask" "F.Paste")
			(net "GND")
		)
		(pad "62" smd rect
			(at -2.050034 -11.474958 90)
			(size 0.519938 1.4986)
			(layers "F.Cu" "F.Mask" "F.Paste")
			(net "M_G_CPU1_ALERT_N")
		)
		(pad "63" smd rect
			(at -2.050034 -10.625074 90)
			(size 0.519938 1.4986)
			(layers "F.Cu" "F.Mask" "F.Paste")
			(net "GND")
		)
		(pad "64" smd rect
			(at -2.050034 -9.774936 90)
			(size 0.519938 1.4986)
			(layers "F.Cu" "F.Mask" "F.Paste")
			(net "M_G_CPU1_SA_CS_N<0>")
		)
		(pad "65" smd rect
			(at -2.050034 -8.925052 90)
			(size 0.519938 1.4986)
			(layers "F.Cu" "F.Mask" "F.Paste")
			(net "GND")
		)
		(pad "66" smd rect
			(at -2.050034 -8.074914 90)
			(size 0.519938 1.4986)
			(layers "F.Cu" "F.Mask" "F.Paste")
			(net "M_G_CPU1_SA_CA<0>")
		)
		(pad "67" smd rect
			(at -2.050034 -7.22503 90)
			(size 0.519938 1.4986)
			(layers "F.Cu" "F.Mask" "F.Paste")
			(net "GND")
		)
		(pad "68" smd rect
			(at -2.050034 -6.374892 90)
			(size 0.519938 1.4986)
			(layers "F.Cu" "F.Mask" "F.Paste")
			(net "M_G_CPU1_SA_CA<2>")
		)
		(pad "69" smd rect
			(at -2.050034 -5.525008 90)
			(size 0.519938 1.4986)
			(layers "F.Cu" "F.Mask" "F.Paste")
			(net "GND")
		)
		(pad "70" smd rect
			(at -2.050034 -4.675124 90)
			(size 0.519938 1.4986)
			(layers "F.Cu" "F.Mask" "F.Paste")
			(net "M_G_CPU1_SA_CA<4>")
		)
		(pad "71" smd rect
			(at -2.050034 -3.824986 90)
			(size 0.519938 1.4986)
			(layers "F.Cu" "F.Mask" "F.Paste")
			(net "GND")
		)
		(pad "72" smd rect
			(at -2.050034 -2.975102 90)
			(size 0.519938 1.4986)
			(layers "F.Cu" "F.Mask" "F.Paste")
			(net "M_G_CPU1_SA_CA<6>")
		)
		(pad "73" smd rect
			(at -2.050034 -2.124964 90)
			(size 0.519938 1.4986)
			(layers "F.Cu" "F.Mask" "F.Paste")
			(net "GND")
		)
		(pad "74" smd rect
			(at -2.050034 -1.27508 90)
			(size 0.519938 1.4986)
			(layers "F.Cu" "F.Mask" "F.Paste")
			(net "M_G_CPU1_SA_PAR")
		)
		(pad "75" smd rect
			(at -2.050034 -0.424942 90)
			(size 0.519938 1.4986)
			(layers "F.Cu" "F.Mask" "F.Paste")
			(net "GND")
		)
		(pad "76" smd rect
			(at -2.050034 5.525008 90)
			(size 0.519938 1.4986)
			(layers "F.Cu" "F.Mask" "F.Paste")
			(net "M_G_CPU1_SB_CA<0>")
		)
		(pad "77" smd rect
			(at -2.050034 6.374892 90)
			(size 0.519938 1.4986)
			(layers "F.Cu" "F.Mask" "F.Paste")
			(net "GND")
		)
		(pad "78" smd rect
			(at -2.050034 7.22503 90)
			(size 0.519938 1.4986)
			(layers "F.Cu" "F.Mask" "F.Paste")
			(net "M_G_CPU1_SB_CA<2>")
		)
		(pad "79" smd rect
			(at -2.050034 8.074914 90)
			(size 0.519938 1.4986)
			(layers "F.Cu" "F.Mask" "F.Paste")
			(net "GND")
		)
		(pad "80" smd rect
			(at -2.050034 8.925052 90)
			(size 0.519938 1.4986)
			(layers "F.Cu" "F.Mask" "F.Paste")
			(net "M_G_CPU1_SB_CA<4>")
		)
		(pad "81" smd rect
			(at -2.050034 9.774936 90)
			(size 0.519938 1.4986)
			(layers "F.Cu" "F.Mask" "F.Paste")
			(net "GND")
		)
		(pad "82" smd rect
			(at -2.050034 10.625074 90)
			(size 0.519938 1.4986)
			(layers "F.Cu" "F.Mask" "F.Paste")
			(net "M_G_CPU1_SB_CA<6>")
		)
		(pad "83" smd rect
			(at -2.050034 11.474958 90)
			(size 0.519938 1.4986)
			(layers "F.Cu" "F.Mask" "F.Paste")
			(net "GND")
		)
		(pad "84" smd rect
			(at -2.050034 12.325096 90)
			(size 0.519938 1.4986)
			(layers "F.Cu" "F.Mask" "F.Paste")
			(net "M_G_CPU1_SB_CS_N<0>")
		)
		(pad "85" smd rect
			(at -2.050034 13.17498 90)
			(size 0.519938 1.4986)
			(layers "F.Cu" "F.Mask" "F.Paste")
			(net "GND")
		)
		(pad "86" smd rect
			(at -2.050034 14.025118 90)
			(size 0.519938 1.4986)
			(layers "F.Cu" "F.Mask" "F.Paste")
			(net "M_G_CPU1_SA_RSP<0>")
		)
		(pad "87" smd rect
			(at -2.050034 14.875002 90)
			(size 0.519938 1.4986)
			(layers "F.Cu" "F.Mask" "F.Paste")
			(net "M_G_CPU1_SB_RSP<0>")
		)
		(pad "88" smd rect
			(at -2.050034 15.724886 90)
			(size 0.519938 1.4986)
			(layers "F.Cu" "F.Mask" "F.Paste")
			(net "GND")
		)
		(pad "89" smd rect
			(at -2.050034 16.575024 90)
			(size 0.519938 1.4986)
			(layers "F.Cu" "F.Mask" "F.Paste")
			(net "M_G_CPU1_SB_CB<4>")
		)
		(pad "90" smd rect
			(at -2.050034 17.424908 90)
			(size 0.519938 1.4986)
			(layers "F.Cu" "F.Mask" "F.Paste")
			(net "GND")
		)
		(pad "91" smd rect
			(at -2.050034 18.275046 90)
			(size 0.519938 1.4986)
			(layers "F.Cu" "F.Mask" "F.Paste")
			(net "M_G_CPU1_SB_CB<5>")
		)
		(pad "92" smd rect
			(at -2.050034 19.12493 90)
			(size 0.519938 1.4986)
			(layers "F.Cu" "F.Mask" "F.Paste")
			(net "GND")
		)
	)
)
